(kicad_pcb
	(version 20241229)
	(generator "pcbnew")
	(generator_version "9.0")
	(general
		(thickness 1.599998)
		(legacy_teardrops no)
	)
	(paper "A4")
	(title_block
		(title "Artix - Datacenter Secure Control Module (DC-SCM)")
		(date "2024-11-06")
		(rev "1.1.3")
		(comment 9 "footprints 334-338 of 544")
	)
	(layers
		(0 "F.Cu" signal)
		(4 "In1.Cu" signal)
		(6 "In2.Cu" signal)
		(8 "In3.Cu" signal)
		(10 "In4.Cu" signal)
		(12 "In5.Cu" signal)
		(14 "In6.Cu" signal)
		(2 "B.Cu" signal)
		(9 "F.Adhes" user "F.Adhesive")
		(11 "B.Adhes" user "B.Adhesive")
		(13 "F.Paste" user)
		(15 "B.Paste" user)
		(5 "F.SilkS" user "F.Silkscreen")
		(7 "B.SilkS" user "B.Silkscreen")
		(1 "F.Mask" user)
		(3 "B.Mask" user)
		(17 "Dwgs.User" user "User.Drawings")
		(19 "Cmts.User" user "User.Comments")
		(21 "Eco1.User" user "User.Eco1")
		(23 "Eco2.User" user "User.Eco2")
		(25 "Edge.Cuts" user)
		(27 "Margin" user)
		(31 "F.CrtYd" user "F.Courtyard")
		(29 "B.CrtYd" user "B.Courtyard")
		(35 "F.Fab" user)
		(33 "B.Fab" user)
	)
	(footprint "antmicro-footprints:C_0201"
		(layer "B.Cu")
		(at 96.375 121.675)
		(descr "Capacitor SMD 0201")
		(tags "capacitor SMD 0201")
		(property "Reference" "C152"
			(at -23.375 0.825 0)
			(layer "B.SilkS")
			(effects
				(font
					(size 0.7 0.7)
					(thickness 0.15)
				)
				(justify right bottom mirror)
			)
		)
		(property "Value" "C_470n_0201"
			(at 0 -1.4 0)
			(layer "B.Fab")
			(effects
				(font
					(size 0.7 0.7)
					(thickness 0.15)
				)
				(justify right bottom mirror)
			)
		)
		(property "Datasheet" "https://product.tdk.com/en/search/capacitor/ceramic/mlcc/info?part_no=C0603X5R1A474M030BC"
			(at 0 0 0)
			(layer "F.Fab")
			(hide yes)
			(effects
				(font
					(size 1.27 1.27)
					(thickness 0.15)
				)
			)
		)
		(property "Description" "SMD Multilayer Ceramic Capacitor, 0.47 µF, 10 V, 0201 [0603 Metric], ± 20%, X5R, C"
			(at 0 0 0)
			(layer "F.Fab")
			(hide yes)
			(effects
				(font
					(size 1.27 1.27)
					(thickness 0.15)
				)
			)
		)
		(property "Author" "Antmicro"
			(at 0 0 0)
			(layer "B.Fab")
			(hide yes)
			(effects
				(font
					(size 1 1)
					(thickness 0.15)
				)
				(justify mirror)
			)
		)
		(property "Dielectric" ""
			(at 0 0 0)
			(layer "B.Fab")
			(hide yes)
			(effects
				(font
					(size 1 1)
					(thickness 0.15)
				)
				(justify mirror)
			)
		)
		(property "License" "Apache-2.0"
			(at 0 0 0)
			(layer "B.Fab")
			(hide yes)
			(effects
				(font
					(size 1 1)
					(thickness 0.15)
				)
				(justify mirror)
			)
		)
		(property "MPN" "C0603X5R1A474M030BC"
			(at 0 0 0)
			(layer "B.Fab")
			(hide yes)
			(effects
				(font
					(size 1 1)
					(thickness 0.15)
				)
				(justify mirror)
			)
		)
		(property "Manufacturer" "TDK"
			(at 0 0 0)
			(layer "B.Fab")
			(hide yes)
			(effects
				(font
					(size 1 1)
					(thickness 0.15)
				)
				(justify mirror)
			)
		)
		(property "Public" "False"
			(at 0 0 0)
			(layer "B.Fab")
			(hide yes)
			(effects
				(font
					(size 1 1)
					(thickness 0.15)
				)
				(justify mirror)
			)
		)
		(property "Val" "470n"
			(at 0 0 0)
			(layer "B.Fab")
			(hide yes)
			(effects
				(font
					(size 1 1)
					(thickness 0.15)
				)
				(justify mirror)
			)
		)
		(property "Voltage" ""
			(at 0 0 0)
			(layer "B.Fab")
			(hide yes)
			(effects
				(font
					(size 1 1)
					(thickness 0.15)
				)
				(justify mirror)
			)
		)
		(property "DNP" ""
			(at 0 0 0)
			(unlocked yes)
			(layer "B.Fab")
			(hide yes)
			(effects
				(font
					(size 1 1)
					(thickness 0.15)
				)
				(justify mirror)
			)
		)
		(sheetname "/FPGA power supply/")
		(sheetfile "fpga-power-supply.kicad_sch")
		(attr smd)
		(fp_rect
			(start -0.7 0.35)
			(end 0.7 -0.35)
			(stroke
				(width 0.05)
				(type default)
			)
			(fill no)
			(layer "B.CrtYd")
		)
		(fp_rect
			(start 0.3 -0.15)
			(end -0.301 0.149)
			(stroke
				(width 0.15)
				(type solid)
			)
			(fill no)
			(layer "B.Fab")
		)
		(pad "" smd roundrect
			(at -0.349 0.002)
			(size 0.318 0.36)
			(layers "B.Paste")
			(roundrect_rratio 0.25)
		)
		(pad "" smd roundrect
			(at 0.341 0.002)
			(size 0.318 0.36)
			(layers "B.Paste")
			(roundrect_rratio 0.25)
		)
		(pad "1" smd roundrect
			(at -0.321 0.002)
			(size 0.46 0.4)
			(layers "B.Cu" "B.Mask")
			(roundrect_rratio 0.25)
			(net 1 "GND")
			(pintype "passive")
		)
		(pad "2" smd roundrect
			(at 0.32 0.002)
			(size 0.46 0.4)
			(layers "B.Cu" "B.Mask")
			(roundrect_rratio 0.25)
			(net 6 "VCC1V0")
			(pintype "passive")
		)
	)
	(footprint "antmicro-footprints:C_0201"
		(layer "B.Cu")
		(at 100.325 120.675)
		(descr "Capacitor SMD 0201")
		(tags "capacitor SMD 0201")
		(property "Reference" "C138"
			(at -21.525 0.625 0)
			(layer "B.SilkS")
			(effects
				(font
					(size 0.7 0.7)
					(thickness 0.15)
				)
				(justify right bottom mirror)
			)
		)
		(property "Value" "C_470n_0201"
			(at 0 -1.4 0)
			(layer "B.Fab")
			(effects
				(font
					(size 0.7 0.7)
					(thickness 0.15)
				)
				(justify right bottom mirror)
			)
		)
		(property "Datasheet" "https://product.tdk.com/en/search/capacitor/ceramic/mlcc/info?part_no=C0603X5R1A474M030BC"
			(at 0 0 0)
			(layer "F.Fab")
			(hide yes)
			(effects
				(font
					(size 1.27 1.27)
					(thickness 0.15)
				)
			)
		)
		(property "Description" "SMD Multilayer Ceramic Capacitor, 0.47 µF, 10 V, 0201 [0603 Metric], ± 20%, X5R, C"
			(at 0 0 0)
			(layer "F.Fab")
			(hide yes)
			(effects
				(font
					(size 1.27 1.27)
					(thickness 0.15)
				)
			)
		)
		(property "Author" "Antmicro"
			(at 0 0 0)
			(layer "B.Fab")
			(hide yes)
			(effects
				(font
					(size 1 1)
					(thickness 0.15)
				)
				(justify mirror)
			)
		)
		(property "Dielectric" ""
			(at 0 0 0)
			(layer "B.Fab")
			(hide yes)
			(effects
				(font
					(size 1 1)
					(thickness 0.15)
				)
				(justify mirror)
			)
		)
		(property "License" "Apache-2.0"
			(at 0 0 0)
			(layer "B.Fab")
			(hide yes)
			(effects
				(font
					(size 1 1)
					(thickness 0.15)
				)
				(justify mirror)
			)
		)
		(property "MPN" "C0603X5R1A474M030BC"
			(at 0 0 0)
			(layer "B.Fab")
			(hide yes)
			(effects
				(font
					(size 1 1)
					(thickness 0.15)
				)
				(justify mirror)
			)
		)
		(property "Manufacturer" "TDK"
			(at 0 0 0)
			(layer "B.Fab")
			(hide yes)
			(effects
				(font
					(size 1 1)
					(thickness 0.15)
				)
				(justify mirror)
			)
		)
		(property "Public" "False"
			(at 0 0 0)
			(layer "B.Fab")
			(hide yes)
			(effects
				(font
					(size 1 1)
					(thickness 0.15)
				)
				(justify mirror)
			)
		)
		(property "Val" "470n"
			(at 0 0 0)
			(layer "B.Fab")
			(hide yes)
			(effects
				(font
					(size 1 1)
					(thickness 0.15)
				)
				(justify mirror)
			)
		)
		(property "Voltage" ""
			(at 0 0 0)
			(layer "B.Fab")
			(hide yes)
			(effects
				(font
					(size 1 1)
					(thickness 0.15)
				)
				(justify mirror)
			)
		)
		(property "DNP" ""
			(at 0 0 0)
			(unlocked yes)
			(layer "B.Fab")
			(hide yes)
			(effects
				(font
					(size 1 1)
					(thickness 0.15)
				)
				(justify mirror)
			)
		)
		(sheetname "/FPGA power supply/")
		(sheetfile "fpga-power-supply.kicad_sch")
		(attr smd)
		(fp_rect
			(start -0.7 0.35)
			(end 0.7 -0.35)
			(stroke
				(width 0.05)
				(type default)
			)
			(fill no)
			(layer "B.CrtYd")
		)
		(fp_rect
			(start 0.3 -0.15)
			(end -0.301 0.149)
			(stroke
				(width 0.15)
				(type solid)
			)
			(fill no)
			(layer "B.Fab")
		)
		(pad "" smd roundrect
			(at -0.349 0.002)
			(size 0.318 0.36)
			(layers "B.Paste")
			(roundrect_rratio 0.25)
		)
		(pad "" smd roundrect
			(at 0.341 0.002)
			(size 0.318 0.36)
			(layers "B.Paste")
			(roundrect_rratio 0.25)
		)
		(pad "1" smd roundrect
			(at -0.321 0.002)
			(size 0.46 0.4)
			(layers "B.Cu" "B.Mask")
			(roundrect_rratio 0.25)
			(net 1 "GND")
			(pintype "passive")
		)
		(pad "2" smd roundrect
			(at 0.32 0.002)
			(size 0.46 0.4)
			(layers "B.Cu" "B.Mask")
			(roundrect_rratio 0.25)
			(net 6 "VCC1V0")
			(pintype "passive")
		)
	)
	(footprint "antmicro-footprints:C_0402_1005Metric"
		(layer "B.Cu")
		(at 98.775 125.275)
		(descr "Capacitor SMD 0402")
		(tags "capacitor SMD 0402")
		(property "Reference" "C167"
			(at -1.375 -0.475 0)
			(layer "B.SilkS")
			(effects
				(font
					(size 0.7 0.7)
					(thickness 0.15)
				)
				(justify right bottom mirror)
			)
		)
		(property "Value" "C_470n_0402"
			(at 0 -1.4 0)
			(layer "B.Fab")
			(effects
				(font
					(size 0.7 0.7)
					(thickness 0.15)
				)
				(justify right bottom mirror)
			)
		)
		(property "Datasheet" "https://product.tdk.com/en/search/capacitor/ceramic/mlcc/info?part_no=C1005X5R1E474M050BB"
			(at 0 0 0)
			(layer "F.Fab")
			(hide yes)
			(effects
				(font
					(size 1.27 1.27)
					(thickness 0.15)
				)
			)
		)
		(property "Description" "SMD Multilayer Ceramic Capacitor, 0.47 µF, 25 V, 0402 [1005 Metric], ± 20%, X5R, C"
			(at 0 0 0)
			(layer "F.Fab")
			(hide yes)
			(effects
				(font
					(size 1.27 1.27)
					(thickness 0.15)
				)
			)
		)
		(property "Author" "Antmicro"
			(at 0 0 0)
			(layer "B.Fab")
			(hide yes)
			(effects
				(font
					(size 1 1)
					(thickness 0.15)
				)
				(justify mirror)
			)
		)
		(property "Dielectric" ""
			(at 0 0 0)
			(layer "B.Fab")
			(hide yes)
			(effects
				(font
					(size 1 1)
					(thickness 0.15)
				)
				(justify mirror)
			)
		)
		(property "License" "Apache-2.0"
			(at 0 0 0)
			(layer "B.Fab")
			(hide yes)
			(effects
				(font
					(size 1 1)
					(thickness 0.15)
				)
				(justify mirror)
			)
		)
		(property "MPN" "C1005X5R1E474M050BB"
			(at 0 0 0)
			(layer "B.Fab")
			(hide yes)
			(effects
				(font
					(size 1 1)
					(thickness 0.15)
				)
				(justify mirror)
			)
		)
		(property "Manufacturer" "TDK"
			(at 0 0 0)
			(layer "B.Fab")
			(hide yes)
			(effects
				(font
					(size 1 1)
					(thickness 0.15)
				)
				(justify mirror)
			)
		)
		(property "Val" "470n"
			(at 0 0 0)
			(layer "B.Fab")
			(hide yes)
			(effects
				(font
					(size 1 1)
					(thickness 0.15)
				)
				(justify mirror)
			)
		)
		(property "Voltage" ""
			(at 0 0 0)
			(layer "B.Fab")
			(hide yes)
			(effects
				(font
					(size 1 1)
					(thickness 0.15)
				)
				(justify mirror)
			)
		)
		(property "DNP" ""
			(at 0 0 0)
			(unlocked yes)
			(layer "B.Fab")
			(hide yes)
			(effects
				(font
					(size 1 1)
					(thickness 0.15)
				)
				(justify mirror)
			)
		)
		(sheetname "/FPGA power supply/")
		(sheetfile "fpga-power-supply.kicad_sch")
		(attr smd)
		(fp_rect
			(start -0.925 0.47)
			(end 0.925 -0.47)
			(stroke
				(width 0.05)
				(type default)
			)
			(fill no)
			(layer "B.CrtYd")
		)
		(fp_line
			(start -0.494 -0.248)
			(end -0.494 0.25)
			(stroke
				(width 0.15)
				(type solid)
			)
			(layer "B.Fab")
		)
		(fp_line
			(start -0.494 0.25)
			(end 0.504 0.25)
			(stroke
				(width 0.15)
				(type solid)
			)
			(layer "B.Fab")
		)
		(fp_line
			(start 0.504 -0.248)
			(end -0.494 -0.248)
			(stroke
				(width 0.15)
				(type solid)
			)
			(layer "B.Fab")
		)
		(fp_line
			(start 0.504 0.25)
			(end 0.504 -0.248)
			(stroke
				(width 0.15)
				(type solid)
			)
			(layer "B.Fab")
		)
		(pad "1" smd roundrect
			(at -0.48 0)
			(size 0.59 0.64)
			(layers "B.Cu" "B.Mask" "B.Paste")
			(roundrect_rratio 0.25)
			(net 1 "GND")
			(pintype "passive")
		)
		(pad "2" smd roundrect
			(at 0.48 0)
			(size 0.59 0.64)
			(layers "B.Cu" "B.Mask" "B.Paste")
			(roundrect_rratio 0.25)
			(net 6 "VCC1V0")
			(pintype "passive")
		)
	)
	(footprint "antmicro-footprints:C_0402_1005Metric"
		(layer "B.Cu")
		(at 104.275 118.675 -90)
		(descr "Capacitor SMD 0402")
		(tags "capacitor SMD 0402")
		(property "Reference" "C141"
			(at -1.575 0.475 90)
			(layer "B.SilkS")
			(effects
				(font
					(size 0.7 0.7)
					(thickness 0.15)
				)
				(justify left bottom mirror)
			)
		)
		(property "Value" "C_470n_0402"
			(at 0 -1.4 90)
			(layer "B.Fab")
			(effects
				(font
					(size 0.7 0.7)
					(thickness 0.15)
				)
				(justify left bottom mirror)
			)
		)
		(property "Datasheet" "https://product.tdk.com/en/search/capacitor/ceramic/mlcc/info?part_no=C1005X5R1E474M050BB"
			(at 0 0 270)
			(layer "F.Fab")
			(hide yes)
			(effects
				(font
					(size 1.27 1.27)
					(thickness 0.15)
				)
			)
		)
		(property "Description" "SMD Multilayer Ceramic Capacitor, 0.47 µF, 25 V, 0402 [1005 Metric], ± 20%, X5R, C"
			(at 0 0 270)
			(layer "F.Fab")
			(hide yes)
			(effects
				(font
					(size 1.27 1.27)
					(thickness 0.15)
				)
			)
		)
		(property "Author" "Antmicro"
			(at -14.4 222.95 0)
			(layer "B.Fab")
			(hide yes)
			(effects
				(font
					(size 1 1)
					(thickness 0.15)
				)
				(justify mirror)
			)
		)
		(property "Dielectric" ""
			(at -14.4 222.95 0)
			(layer "B.Fab")
			(hide yes)
			(effects
				(font
					(size 1 1)
					(thickness 0.15)
				)
				(justify mirror)
			)
		)
		(property "License" "Apache-2.0"
			(at -14.4 222.95 0)
			(layer "B.Fab")
			(hide yes)
			(effects
				(font
					(size 1 1)
					(thickness 0.15)
				)
				(justify mirror)
			)
		)
		(property "MPN" "C1005X5R1E474M050BB"
			(at -14.4 222.95 0)
			(layer "B.Fab")
			(hide yes)
			(effects
				(font
					(size 1 1)
					(thickness 0.15)
				)
				(justify mirror)
			)
		)
		(property "Manufacturer" "TDK"
			(at -14.4 222.95 0)
			(layer "B.Fab")
			(hide yes)
			(effects
				(font
					(size 1 1)
					(thickness 0.15)
				)
				(justify mirror)
			)
		)
		(property "Val" "470n"
			(at -14.4 222.95 0)
			(layer "B.Fab")
			(hide yes)
			(effects
				(font
					(size 1 1)
					(thickness 0.15)
				)
				(justify mirror)
			)
		)
		(property "Voltage" ""
			(at -14.4 222.95 0)
			(layer "B.Fab")
			(hide yes)
			(effects
				(font
					(size 1 1)
					(thickness 0.15)
				)
				(justify mirror)
			)
		)
		(sheetname "/FPGA power supply/")
		(sheetfile "fpga-power-supply.kicad_sch")
		(attr smd)
		(fp_rect
			(start -0.925 0.47)
			(end 0.925 -0.47)
			(stroke
				(width 0.05)
				(type default)
			)
			(fill no)
			(layer "B.CrtYd")
		)
		(fp_line
			(start -0.494 0.25)
			(end 0.504 0.25)
			(stroke
				(width 0.15)
				(type solid)
			)
			(layer "B.Fab")
		)
		(fp_line
			(start 0.504 0.25)
			(end 0.504 -0.248)
			(stroke
				(width 0.15)
				(type solid)
			)
			(layer "B.Fab")
		)
		(fp_line
			(start -0.494 -0.248)
			(end -0.494 0.25)
			(stroke
				(width 0.15)
				(type solid)
			)
			(layer "B.Fab")
		)
		(fp_line
			(start 0.504 -0.248)
			(end -0.494 -0.248)
			(stroke
				(width 0.15)
				(type solid)
			)
			(layer "B.Fab")
		)
		(pad "1" smd roundrect
			(at -0.48 0 270)
			(size 0.59 0.64)
			(layers "B.Cu" "B.Mask" "B.Paste")
			(roundrect_rratio 0.25)
			(net 1 "GND")
			(pintype "passive")
		)
		(pad "2" smd roundrect
			(at 0.48 0 270)
			(size 0.59 0.64)
			(layers "B.Cu" "B.Mask" "B.Paste")
			(roundrect_rratio 0.25)
			(net 5 "VCC1V8")
			(pintype "passive")
		)
	)
	(footprint "antmicro-footprints:C_0402_1005Metric"
		(layer "B.Cu")
		(at 98.275 118.475 -90)
		(descr "Capacitor SMD 0402")
		(tags "capacitor SMD 0402")
		(property "Reference" "C143"
			(at -1.575 0.475 90)
			(layer "B.SilkS")
			(effects
				(font
					(size 0.7 0.7)
					(thickness 0.15)
				)
				(justify left bottom mirror)
			)
		)
		(property "Value" "C_470n_0402"
			(at 0 -1.4 90)
			(layer "B.Fab")
			(effects
				(font
					(size 0.7 0.7)
					(thickness 0.15)
				)
				(justify left bottom mirror)
			)
		)
		(property "Datasheet" "https://product.tdk.com/en/search/capacitor/ceramic/mlcc/info?part_no=C1005X5R1E474M050BB"
			(at 0 0 270)
			(layer "F.Fab")
			(hide yes)
			(effects
				(font
					(size 1.27 1.27)
					(thickness 0.15)
				)
			)
		)
		(property "Description" "SMD Multilayer Ceramic Capacitor, 0.47 µF, 25 V, 0402 [1005 Metric], ± 20%, X5R, C"
			(at 0 0 270)
			(layer "F.Fab")
			(hide yes)
			(effects
				(font
					(size 1.27 1.27)
					(thickness 0.15)
				)
			)
		)
		(property "Author" "Antmicro"
			(at -20.2 216.75 0)
			(layer "B.Fab")
			(hide yes)
			(effects
				(font
					(size 1 1)
					(thickness 0.15)
				)
				(justify mirror)
			)
		)
		(property "Dielectric" ""
			(at -20.2 216.75 0)
			(layer "B.Fab")
			(hide yes)
			(effects
				(font
					(size 1 1)
					(thickness 0.15)
				)
				(justify mirror)
			)
		)
		(property "License" "Apache-2.0"
			(at -20.2 216.75 0)
			(layer "B.Fab")
			(hide yes)
			(effects
				(font
					(size 1 1)
					(thickness 0.15)
				)
				(justify mirror)
			)
		)
		(property "MPN" "C1005X5R1E474M050BB"
			(at -20.2 216.75 0)
			(layer "B.Fab")
			(hide yes)
			(effects
				(font
					(size 1 1)
					(thickness 0.15)
				)
				(justify mirror)
			)
		)
		(property "Manufacturer" "TDK"
			(at -20.2 216.75 0)
			(layer "B.Fab")
			(hide yes)
			(effects
				(font
					(size 1 1)
					(thickness 0.15)
				)
				(justify mirror)
			)
		)
		(property "Val" "470n"
			(at -20.2 216.75 0)
			(layer "B.Fab")
			(hide yes)
			(effects
				(font
					(size 1 1)
					(thickness 0.15)
				)
				(justify mirror)
			)
		)
		(property "Voltage" ""
			(at -20.2 216.75 0)
			(layer "B.Fab")
			(hide yes)
			(effects
				(font
					(size 1 1)
					(thickness 0.15)
				)
				(justify mirror)
			)
		)
		(sheetname "/FPGA power supply/")
		(sheetfile "fpga-power-supply.kicad_sch")
		(attr smd)
		(fp_rect
			(start -0.925 0.47)
			(end 0.925 -0.47)
			(stroke
				(width 0.05)
				(type default)
			)
			(fill no)
			(layer "B.CrtYd")
		)
		(fp_line
			(start -0.494 0.25)
			(end 0.504 0.25)
			(stroke
				(width 0.15)
				(type solid)
			)
			(layer "B.Fab")
		)
		(fp_line
			(start 0.504 0.25)
			(end 0.504 -0.248)
			(stroke
				(width 0.15)
				(type solid)
			)
			(layer "B.Fab")
		)
		(fp_line
			(start -0.494 -0.248)
			(end -0.494 0.25)
			(stroke
				(width 0.15)
				(type solid)
			)
			(layer "B.Fab")
		)
		(fp_line
			(start 0.504 -0.248)
			(end -0.494 -0.248)
			(stroke
				(width 0.15)
				(type solid)
			)
			(layer "B.Fab")
		)
		(pad "1" smd roundrect
			(at -0.48 0 270)
			(size 0.59 0.64)
			(layers "B.Cu" "B.Mask" "B.Paste")
			(roundrect_rratio 0.25)
			(net 1 "GND")
			(pintype "passive")
		)
		(pad "2" smd roundrect
			(at 0.48 0 270)
			(size 0.59 0.64)
			(layers "B.Cu" "B.Mask" "B.Paste")
			(roundrect_rratio 0.25)
			(net 5 "VCC1V8")
			(pintype "passive")
		)
	)
)
